# S9S_MB_2U (Grand Teton) — schematic netlist excerpt (pin names and nets, part order shuffled) for the footprints in the layout excerpt that follows; sources: Cadence DE-HDL packaged netlist, KiCad conversion of 03242023_DA0F0TMBIJ0_F0T_Motherboard_J_brd_V01_OCP.brd

R3637  Q_RES  0 5% CHIP  pkg 0402LF  page 206 : A = OCP_SFF_CLK_OE_N ; B = FM_DB2000_12_OE_N
R2812  Q_RES  33.2 1% CHIP  pkg 0402LF  page 245 : A = SMB_FAN_3V3AUX_BUF_SDA ; B = SMB_FAN_3V3AUX_BUF_R_SDA

(kicad_pcb
	(version 20260206)
	(generator "pcbnew")
	(generator_version "10.0")
	(general
		(thickness 1.6)
		(legacy_teardrops no)
	)
	(paper "A4")
	(title_block
		(title "03242023_DA0F0TMBIJ0_F0T_Motherboard_J_brd_V01_OCP.brd")
		(comment 1 "Grand Teton / footprints 4643-4644 of 6105")
	)
	(layers
		(0 "F.Cu" signal "TOP")
		(4 "In1.Cu" signal "GND")
		(6 "In2.Cu" signal "IN1")
		(8 "In3.Cu" signal "GND1")
		(10 "In4.Cu" signal "IN2")
		(12 "In5.Cu" signal "GND2")
		(14 "In6.Cu" signal "IN3")
		(16 "In7.Cu" signal "GND3")
		(18 "In8.Cu" signal "VCC")
		(20 "In9.Cu" signal "VCC1")
		(22 "In10.Cu" signal "GND4")
		(24 "In11.Cu" signal "IN4")
		(26 "In12.Cu" signal "GND5")
		(28 "In13.Cu" signal "IN5")
		(30 "In14.Cu" signal "GND6")
		(32 "In15.Cu" signal "IN6")
		(34 "In16.Cu" signal "GND7")
		(2 "B.Cu" signal "BOTTOM")
		(9 "F.Adhes" user "F.Adhesive")
		(11 "B.Adhes" user "B.Adhesive")
		(13 "F.Paste" user "Package Geometry/Pastemask Top")
		(15 "B.Paste" user "Package Geometry/Pastemask Bottom")
		(5 "F.SilkS" user "Ref Des/Silkscreen Top")
		(7 "B.SilkS" user "Ref Des/Silkscreen Bottom")
		(1 "F.Mask" user "Board Geometry/Soldermask Top")
		(3 "B.Mask" user "Board Geometry/Soldermask Bottom")
		(17 "Dwgs.User" user "User.Drawings")
		(19 "Cmts.User" user "User.Comments")
		(21 "Eco1.User" user "User.Eco1")
		(23 "Eco2.User" user "User.Eco2")
		(25 "Edge.Cuts" user "Board Geometry/Outline")
		(27 "Margin" user)
		(31 "F.CrtYd" user "Package Geometry/Place Bound Top")
		(29 "B.CrtYd" user "Package Geometry/Place Bound Bottom")
		(35 "F.Fab" user "Ref Des/Assembly Top")
		(33 "B.Fab" user "Ref Des/Assembly Bottom")
	)
	(footprint ""
		(layer "B.Cu")
		(at 231.52608 -118.760748 -90)
		(property "Reference" "R3637"
			(at 0 0 90)
			(layer "B.SilkS")
			(hide yes)
			(effects
				(font
					(size 1.27 1.27)
				)
				(justify mirror)
			)
		)
		(property "Value" ""
			(at 0 0 90)
			(layer "B.Fab")
			(effects
				(font
					(size 1.27 1.27)
				)
				(justify mirror)
			)
		)
		(duplicate_pad_numbers_are_jumpers no)
		(fp_line
			(start -0.7874 0.4064)
			(end 0.7874 0.4064)
			(stroke
				(width 0.1524)
				(type default)
			)
			(layer "B.SilkS")
		)
		(fp_line
			(start 0.7874 0.4064)
			(end 0.7874 -0.4064)
			(stroke
				(width 0.1524)
				(type default)
			)
			(layer "B.SilkS")
		)
		(fp_line
			(start -0.7874 -0.4064)
			(end -0.7874 0.4064)
			(stroke
				(width 0.1524)
				(type default)
			)
			(layer "B.SilkS")
		)
		(fp_line
			(start 0.7874 -0.4064)
			(end -0.7874 -0.4064)
			(stroke
				(width 0.1524)
				(type default)
			)
			(layer "B.SilkS")
		)
		(fp_line
			(start -0.67945 0.3048)
			(end -0.120396 0.3048)
			(stroke
				(width 0.1)
				(type default)
			)
			(layer "B.Fab")
		)
		(fp_line
			(start -0.120396 0.3048)
			(end -0.120396 0.2794)
			(stroke
				(width 0.1)
				(type default)
			)
			(layer "B.Fab")
		)
		(fp_line
			(start 0.12065 0.3048)
			(end 0.67945 0.3048)
			(stroke
				(width 0.1)
				(type default)
			)
			(layer "B.Fab")
		)
		(fp_line
			(start 0.67945 0.3048)
			(end 0.67945 -0.305054)
			(stroke
				(width 0.1)
				(type default)
			)
			(layer "B.Fab")
		)
		(fp_line
			(start -0.120396 0.2794)
			(end 0.12065 0.2794)
			(stroke
				(width 0.1)
				(type default)
			)
			(layer "B.Fab")
		)
		(fp_line
			(start 0.12065 0.2794)
			(end 0.12065 0.3048)
			(stroke
				(width 0.1)
				(type default)
			)
			(layer "B.Fab")
		)
		(fp_line
			(start -0.12065 -0.2794)
			(end -0.12065 -0.3048)
			(stroke
				(width 0.1)
				(type default)
			)
			(layer "B.Fab")
		)
		(fp_line
			(start 0.12065 -0.2794)
			(end -0.12065 -0.2794)
			(stroke
				(width 0.1)
				(type default)
			)
			(layer "B.Fab")
		)
		(fp_line
			(start -0.67945 -0.3048)
			(end -0.67945 0.3048)
			(stroke
				(width 0.1)
				(type default)
			)
			(layer "B.Fab")
		)
		(fp_line
			(start -0.12065 -0.3048)
			(end -0.67945 -0.3048)
			(stroke
				(width 0.1)
				(type default)
			)
			(layer "B.Fab")
		)
		(fp_line
			(start 0.12065 -0.305054)
			(end 0.12065 -0.2794)
			(stroke
				(width 0.1)
				(type default)
			)
			(layer "B.Fab")
		)
		(fp_line
			(start 0.67945 -0.305054)
			(end 0.12065 -0.305054)
			(stroke
				(width 0.1)
				(type default)
			)
			(layer "B.Fab")
		)
		(pad "1" smd circle
			(at 0.40005 0 90)
			(size 0 0)
			(layers "B.Cu" "B.Mask" "B.Paste")
			(net "OCP_SFF_CLK_OE_N")
		)
		(pad "2" smd circle
			(at -0.40005 0 90)
			(size 0 0)
			(layers "B.Cu" "B.Mask" "B.Paste")
			(net "FM_DB2000_12_OE_N")
		)
	)
	(footprint ""
		(layer "B.Cu")
		(at 178.871626 -415.633154 90)
		(property "Reference" "R2812"
			(at 0 0 90)
			(layer "B.SilkS")
			(hide yes)
			(effects
				(font
					(size 1.27 1.27)
				)
				(justify mirror)
			)
		)
		(property "Value" ""
			(at 0 0 90)
			(layer "B.Fab")
			(effects
				(font
					(size 1.27 1.27)
				)
				(justify mirror)
			)
		)
		(duplicate_pad_numbers_are_jumpers no)
		(fp_line
			(start 0.7874 -0.4064)
			(end -0.7874 -0.4064)
			(stroke
				(width 0.1524)
				(type default)
			)
			(layer "B.SilkS")
		)
		(fp_line
			(start -0.7874 -0.4064)
			(end -0.7874 0.4064)
			(stroke
				(width 0.1524)
				(type default)
			)
			(layer "B.SilkS")
		)
		(fp_line
			(start 0.7874 0.4064)
			(end 0.7874 -0.4064)
			(stroke
				(width 0.1524)
				(type default)
			)
			(layer "B.SilkS")
		)
		(fp_line
			(start -0.7874 0.4064)
			(end 0.7874 0.4064)
			(stroke
				(width 0.1524)
				(type default)
			)
			(layer "B.SilkS")
		)
		(fp_line
			(start 0.67945 -0.305054)
			(end 0.12065 -0.305054)
			(stroke
				(width 0.1)
				(type default)
			)
			(layer "B.Fab")
		)
		(fp_line
			(start 0.12065 -0.305054)
			(end 0.12065 -0.2794)
			(stroke
				(width 0.1)
				(type default)
			)
			(layer "B.Fab")
		)
		(fp_line
			(start -0.12065 -0.3048)
			(end -0.67945 -0.3048)
			(stroke
				(width 0.1)
				(type default)
			)
			(layer "B.Fab")
		)
		(fp_line
			(start -0.67945 -0.3048)
			(end -0.67945 0.3048)
			(stroke
				(width 0.1)
				(type default)
			)
			(layer "B.Fab")
		)
		(fp_line
			(start 0.12065 -0.2794)
			(end -0.12065 -0.2794)
			(stroke
				(width 0.1)
				(type default)
			)
			(layer "B.Fab")
		)
		(fp_line
			(start -0.12065 -0.2794)
			(end -0.12065 -0.3048)
			(stroke
				(width 0.1)
				(type default)
			)
			(layer "B.Fab")
		)
		(fp_line
			(start 0.12065 0.2794)
			(end 0.12065 0.3048)
			(stroke
				(width 0.1)
				(type default)
			)
			(layer "B.Fab")
		)
		(fp_line
			(start -0.120396 0.2794)
			(end 0.12065 0.2794)
			(stroke
				(width 0.1)
				(type default)
			)
			(layer "B.Fab")
		)
		(fp_line
			(start 0.67945 0.3048)
			(end 0.67945 -0.305054)
			(stroke
				(width 0.1)
				(type default)
			)
			(layer "B.Fab")
		)
		(fp_line
			(start 0.12065 0.3048)
			(end 0.67945 0.3048)
			(stroke
				(width 0.1)
				(type default)
			)
			(layer "B.Fab")
		)
		(fp_line
			(start -0.120396 0.3048)
			(end -0.120396 0.2794)
			(stroke
				(width 0.1)
				(type default)
			)
			(layer "B.Fab")
		)
		(fp_line
			(start -0.67945 0.3048)
			(end -0.120396 0.3048)
			(stroke
				(width 0.1)
				(type default)
			)
			(layer "B.Fab")
		)
		(pad "1" smd circle
			(at 0.40005 0 270)
			(size 0 0)
			(layers "B.Cu" "B.Mask" "B.Paste")
			(net "SMB_FAN_3V3AUX_BUF_SDA")
		)
		(pad "2" smd circle
			(at -0.40005 0 270)
			(size 0 0)
			(layers "B.Cu" "B.Mask" "B.Paste")
			(net "SMB_FAN_3V3AUX_BUF_R_SDA")
		)
	)
)
